(kicad_pcb
	(version 20260206)
	(generator "pcbnew")
	(generator_version "10.0")
	(general
		(thickness 1.6)
		(legacy_teardrops no)
	)
	(paper "A4")
	(title_block
		(title "9054_F0T_PDB_BD_GPU_F_V04_1213_1550_OCP.brd")
		(comment 1 "Grand Teton / footprints 220-227 of 608")
	)
	(layers
		(0 "F.Cu" signal "TOP")
		(4 "In1.Cu" signal "GND")
		(6 "In2.Cu" signal "IN1")
		(8 "In3.Cu" signal "GND1")
		(10 "In4.Cu" signal "VCC")
		(12 "In5.Cu" signal "VCC1")
		(14 "In6.Cu" signal "GND2")
		(16 "In7.Cu" signal "IN2")
		(18 "In8.Cu" signal "GND3")
		(2 "B.Cu" signal "BOTTOM")
		(9 "F.Adhes" user "F.Adhesive")
		(11 "B.Adhes" user "B.Adhesive")
		(13 "F.Paste" user "Package Geometry/Pastemask Top")
		(15 "B.Paste" user "Package Geometry/Pastemask Bottom")
		(5 "F.SilkS" user "Ref Des/Silkscreen Top")
		(7 "B.SilkS" user "Ref Des/Silkscreen Bottom")
		(1 "F.Mask" user "Board Geometry/Soldermask Top")
		(3 "B.Mask" user "Board Geometry/Soldermask Bottom")
		(17 "Dwgs.User" user "User.Drawings")
		(19 "Cmts.User" user "User.Comments")
		(21 "Eco1.User" user "User.Eco1")
		(23 "Eco2.User" user "User.Eco2")
		(25 "Edge.Cuts" user "Board Geometry/Outline")
		(27 "Margin" user)
		(31 "F.CrtYd" user "Package Geometry/Place Bound Top")
		(29 "B.CrtYd" user "Package Geometry/Place Bound Bottom")
		(35 "F.Fab" user "Ref Des/Assembly Top")
		(33 "B.Fab" user "Ref Des/Assembly Bottom")
	)
	(footprint ""
		(layer "F.Cu")
		(at 402.717 -21.59)
		(property "Reference" "PR100"
			(at -7.7216 1.55067 0)
			(unlocked yes)
			(layer "F.SilkS")
			(effects
				(font
					(size 0.7874 0.5842)
					(thickness 0.1524)
				)
				(justify left)
			)
		)
		(property "Value" ""
			(at 0 0 0)
			(layer "F.Fab")
			(effects
				(font
					(size 1.27 1.27)
				)
			)
		)
		(duplicate_pad_numbers_are_jumpers no)
		(fp_line
			(start -3.62712 -1.8796)
			(end -3.62712 1.8796)
			(stroke
				(width 0.1524)
				(type default)
			)
			(layer "F.SilkS")
		)
		(fp_line
			(start -3.62712 1.8796)
			(end 3.62712 1.8796)
			(stroke
				(width 0.1524)
				(type default)
			)
			(layer "F.SilkS")
		)
		(fp_line
			(start 3.62712 -1.8796)
			(end -3.62712 -1.8796)
			(stroke
				(width 0.1524)
				(type default)
			)
			(layer "F.SilkS")
		)
		(fp_line
			(start 3.62712 1.8796)
			(end 3.62712 -1.8796)
			(stroke
				(width 0.1524)
				(type default)
			)
			(layer "F.SilkS")
		)
		(fp_line
			(start -3.299968 -1.700022)
			(end -3.299968 1.700022)
			(stroke
				(width 0.1)
				(type default)
			)
			(layer "F.Fab")
		)
		(fp_line
			(start -3.299968 1.700022)
			(end 3.299968 1.700022)
			(stroke
				(width 0.1)
				(type default)
			)
			(layer "F.Fab")
		)
		(fp_line
			(start 3.299968 -1.700022)
			(end -3.299968 -1.700022)
			(stroke
				(width 0.1)
				(type default)
			)
			(layer "F.Fab")
		)
		(fp_line
			(start 3.299968 1.700022)
			(end 3.299968 -1.700022)
			(stroke
				(width 0.1)
				(type default)
			)
			(layer "F.Fab")
		)
		(pad "1" smd rect
			(at -2.70002 0)
			(size 1.6002 3.5052)
			(layers "F.Cu" "F.Mask" "F.Paste")
			(net "P52V_HS1_EN_DISCHARGE_VBE_R")
		)
		(pad "2" smd rect
			(at 2.70002 0)
			(size 1.6002 3.5052)
			(layers "F.Cu" "F.Mask" "F.Paste")
			(net "GND")
		)
	)
	(footprint ""
		(layer "F.Cu")
		(at 427.228 -40.386)
		(property "Reference" "R136"
			(at 0 0 0)
			(layer "F.SilkS")
			(hide yes)
			(effects
				(font
					(size 1.27 1.27)
				)
			)
		)
		(property "Value" ""
			(at 0 0 0)
			(layer "F.Fab")
			(effects
				(font
					(size 1.27 1.27)
				)
			)
		)
		(duplicate_pad_numbers_are_jumpers no)
		(fp_line
			(start -0.7874 -0.4064)
			(end 0.7874 -0.4064)
			(stroke
				(width 0.1524)
				(type default)
			)
			(layer "F.SilkS")
		)
		(fp_line
			(start -0.7874 0.4064)
			(end -0.7874 -0.4064)
			(stroke
				(width 0.1524)
				(type default)
			)
			(layer "F.SilkS")
		)
		(fp_line
			(start 0.7874 -0.4064)
			(end 0.7874 0.4064)
			(stroke
				(width 0.1524)
				(type default)
			)
			(layer "F.SilkS")
		)
		(fp_line
			(start 0.7874 0.4064)
			(end -0.7874 0.4064)
			(stroke
				(width 0.1524)
				(type default)
			)
			(layer "F.SilkS")
		)
		(fp_line
			(start -0.67945 -0.305054)
			(end -0.12065 -0.305054)
			(stroke
				(width 0.1)
				(type default)
			)
			(layer "F.Fab")
		)
		(fp_line
			(start -0.67945 0.3048)
			(end -0.67945 -0.305054)
			(stroke
				(width 0.1)
				(type default)
			)
			(layer "F.Fab")
		)
		(fp_line
			(start -0.12065 -0.305054)
			(end -0.12065 -0.2794)
			(stroke
				(width 0.1)
				(type default)
			)
			(layer "F.Fab")
		)
		(fp_line
			(start -0.12065 -0.2794)
			(end 0.12065 -0.2794)
			(stroke
				(width 0.1)
				(type default)
			)
			(layer "F.Fab")
		)
		(fp_line
			(start -0.12065 0.2794)
			(end -0.12065 0.3048)
			(stroke
				(width 0.1)
				(type default)
			)
			(layer "F.Fab")
		)
		(fp_line
			(start -0.12065 0.3048)
			(end -0.67945 0.3048)
			(stroke
				(width 0.1)
				(type default)
			)
			(layer "F.Fab")
		)
		(fp_line
			(start 0.120396 0.2794)
			(end -0.12065 0.2794)
			(stroke
				(width 0.1)
				(type default)
			)
			(layer "F.Fab")
		)
		(fp_line
			(start 0.120396 0.3048)
			(end 0.120396 0.2794)
			(stroke
				(width 0.1)
				(type default)
			)
			(layer "F.Fab")
		)
		(fp_line
			(start 0.12065 -0.3048)
			(end 0.67945 -0.3048)
			(stroke
				(width 0.1)
				(type default)
			)
			(layer "F.Fab")
		)
		(fp_line
			(start 0.12065 -0.2794)
			(end 0.12065 -0.3048)
			(stroke
				(width 0.1)
				(type default)
			)
			(layer "F.Fab")
		)
		(fp_line
			(start 0.67945 -0.3048)
			(end 0.67945 0.3048)
			(stroke
				(width 0.1)
				(type default)
			)
			(layer "F.Fab")
		)
		(fp_line
			(start 0.67945 0.3048)
			(end 0.120396 0.3048)
			(stroke
				(width 0.1)
				(type default)
			)
			(layer "F.Fab")
		)
		(pad "1" smd circle
			(at -0.40005 0)
			(size 0 0)
			(layers "F.Cu" "F.Mask" "F.Paste")
			(net "BOARD_ID_2")
		)
		(pad "2" smd circle
			(at 0.40005 0)
			(size 0 0)
			(layers "F.Cu" "F.Mask" "F.Paste")
			(net "GND")
		)
	)
	(footprint ""
		(layer "F.Cu")
		(at 378.079 -119.38)
		(property "Reference" "PC30"
			(at 5.3594 -4.67233 0)
			(unlocked yes)
			(layer "F.SilkS")
			(effects
				(font
					(size 0.7874 0.5842)
					(thickness 0.1524)
				)
				(justify left)
			)
		)
		(property "Value" ""
			(at 0 0 0)
			(layer "F.Fab")
			(effects
				(font
					(size 1.27 1.27)
				)
			)
		)
		(duplicate_pad_numbers_are_jumpers no)
		(fp_line
			(start -9.253728 3.750056)
			(end 9.249918 3.750056)
			(stroke
				(width 0.1524)
				(type default)
			)
			(layer "F.SilkS")
		)
		(fp_line
			(start 0 3.750056)
			(end -9.253728 3.750056)
			(stroke
				(width 0.1524)
				(type default)
			)
			(layer "F.SilkS")
		)
		(fp_circle
			(center 0 3.750056)
			(end 9.249918 3.750056)
			(stroke
				(width 0.1524)
				(type default)
			)
			(fill no)
			(layer "F.SilkS")
		)
		(fp_poly
			(pts
				(arc
					(start 9.249918 3.750056)
					(mid 0 12.999974)
					(end -9.249918 3.750056)
				)
			)
			(stroke
				(width 0)
				(type default)
			)
			(fill yes)
			(layer "F.SilkS")
		)
		(fp_circle
			(center 0 3.750056)
			(end 9.249918 3.750056)
			(stroke
				(width 0.1)
				(type default)
			)
			(fill no)
			(layer "F.Fab")
		)
		(pad "1" thru_hole rect
			(at 0 0)
			(size 1.778 1.778)
			(drill 1.27)
			(layers "*.Cu" "*.Mask")
			(remove_unused_layers no)
			(net "P52V_HS1")
			(clearance 0)
			(padstack
				(mode front_inner_back)
				(layer "Inner"
					(shape circle)
					(size 1.778 1.778)
					(clearance 0)
				)
				(layer "B.Cu"
					(shape rect)
					(size 1.778 1.778)
					(clearance 0)
				)
			)
		)
		(pad "2" thru_hole circle
			(at 0 7.500112)
			(size 1.778 1.778)
			(drill 1.27)
			(layers "*.Cu" "*.Mask")
			(remove_unused_layers no)
			(net "GND")
			(clearance 0)
		)
	)
	(footprint ""
		(layer "F.Cu")
		(at 427.228 -44.577)
		(property "Reference" "R99"
			(at 0 0 0)
			(layer "F.SilkS")
			(hide yes)
			(effects
				(font
					(size 1.27 1.27)
				)
			)
		)
		(property "Value" ""
			(at 0 0 0)
			(layer "F.Fab")
			(effects
				(font
					(size 1.27 1.27)
				)
			)
		)
		(duplicate_pad_numbers_are_jumpers no)
		(fp_line
			(start -0.7874 -0.4064)
			(end 0.7874 -0.4064)
			(stroke
				(width 0.1524)
				(type default)
			)
			(layer "F.SilkS")
		)
		(fp_line
			(start -0.7874 0.4064)
			(end -0.7874 -0.4064)
			(stroke
				(width 0.1524)
				(type default)
			)
			(layer "F.SilkS")
		)
		(fp_line
			(start 0.7874 -0.4064)
			(end 0.7874 0.4064)
			(stroke
				(width 0.1524)
				(type default)
			)
			(layer "F.SilkS")
		)
		(fp_line
			(start 0.7874 0.4064)
			(end -0.7874 0.4064)
			(stroke
				(width 0.1524)
				(type default)
			)
			(layer "F.SilkS")
		)
		(fp_line
			(start -0.67945 -0.305054)
			(end -0.12065 -0.305054)
			(stroke
				(width 0.1)
				(type default)
			)
			(layer "F.Fab")
		)
		(fp_line
			(start -0.67945 0.3048)
			(end -0.67945 -0.305054)
			(stroke
				(width 0.1)
				(type default)
			)
			(layer "F.Fab")
		)
		(fp_line
			(start -0.12065 -0.305054)
			(end -0.12065 -0.2794)
			(stroke
				(width 0.1)
				(type default)
			)
			(layer "F.Fab")
		)
		(fp_line
			(start -0.12065 -0.2794)
			(end 0.12065 -0.2794)
			(stroke
				(width 0.1)
				(type default)
			)
			(layer "F.Fab")
		)
		(fp_line
			(start -0.12065 0.2794)
			(end -0.12065 0.3048)
			(stroke
				(width 0.1)
				(type default)
			)
			(layer "F.Fab")
		)
		(fp_line
			(start -0.12065 0.3048)
			(end -0.67945 0.3048)
			(stroke
				(width 0.1)
				(type default)
			)
			(layer "F.Fab")
		)
		(fp_line
			(start 0.120396 0.2794)
			(end -0.12065 0.2794)
			(stroke
				(width 0.1)
				(type default)
			)
			(layer "F.Fab")
		)
		(fp_line
			(start 0.120396 0.3048)
			(end 0.120396 0.2794)
			(stroke
				(width 0.1)
				(type default)
			)
			(layer "F.Fab")
		)
		(fp_line
			(start 0.12065 -0.3048)
			(end 0.67945 -0.3048)
			(stroke
				(width 0.1)
				(type default)
			)
			(layer "F.Fab")
		)
		(fp_line
			(start 0.12065 -0.2794)
			(end 0.12065 -0.3048)
			(stroke
				(width 0.1)
				(type default)
			)
			(layer "F.Fab")
		)
		(fp_line
			(start 0.67945 -0.3048)
			(end 0.67945 0.3048)
			(stroke
				(width 0.1)
				(type default)
			)
			(layer "F.Fab")
		)
		(fp_line
			(start 0.67945 0.3048)
			(end 0.120396 0.3048)
			(stroke
				(width 0.1)
				(type default)
			)
			(layer "F.Fab")
		)
		(pad "1" smd circle
			(at -0.40005 0)
			(size 0 0)
			(layers "F.Cu" "F.Mask" "F.Paste")
			(net "SKU_ID_2")
		)
		(pad "2" smd circle
			(at 0.40005 0)
			(size 0 0)
			(layers "F.Cu" "F.Mask" "F.Paste")
			(net "GND")
		)
	)
	(footprint ""
		(layer "F.Cu")
		(at 80.518 -17.907 -90)
		(property "Reference" "R75"
			(at 0 0 270)
			(layer "F.SilkS")
			(hide yes)
			(effects
				(font
					(size 1.27 1.27)
				)
			)
		)
		(property "Value" ""
			(at 0 0 270)
			(layer "F.Fab")
			(effects
				(font
					(size 1.27 1.27)
				)
			)
		)
		(duplicate_pad_numbers_are_jumpers no)
		(fp_line
			(start -0.7874 0.4064)
			(end -0.7874 -0.4064)
			(stroke
				(width 0.1524)
				(type default)
			)
			(layer "F.SilkS")
		)
		(fp_line
			(start 0.7874 0.4064)
			(end -0.7874 0.4064)
			(stroke
				(width 0.1524)
				(type default)
			)
			(layer "F.SilkS")
		)
		(fp_line
			(start -0.7874 -0.4064)
			(end 0.7874 -0.4064)
			(stroke
				(width 0.1524)
				(type default)
			)
			(layer "F.SilkS")
		)
		(fp_line
			(start 0.7874 -0.4064)
			(end 0.7874 0.4064)
			(stroke
				(width 0.1524)
				(type default)
			)
			(layer "F.SilkS")
		)
		(fp_line
			(start -0.67945 0.3048)
			(end -0.67945 -0.305054)
			(stroke
				(width 0.1)
				(type default)
			)
			(layer "F.Fab")
		)
		(fp_line
			(start -0.12065 0.3048)
			(end -0.67945 0.3048)
			(stroke
				(width 0.1)
				(type default)
			)
			(layer "F.Fab")
		)
		(fp_line
			(start 0.120396 0.3048)
			(end 0.120396 0.2794)
			(stroke
				(width 0.1)
				(type default)
			)
			(layer "F.Fab")
		)
		(fp_line
			(start 0.67945 0.3048)
			(end 0.120396 0.3048)
			(stroke
				(width 0.1)
				(type default)
			)
			(layer "F.Fab")
		)
		(fp_line
			(start -0.12065 0.2794)
			(end -0.12065 0.3048)
			(stroke
				(width 0.1)
				(type default)
			)
			(layer "F.Fab")
		)
		(fp_line
			(start 0.120396 0.2794)
			(end -0.12065 0.2794)
			(stroke
				(width 0.1)
				(type default)
			)
			(layer "F.Fab")
		)
		(fp_line
			(start -0.12065 -0.2794)
			(end 0.12065 -0.2794)
			(stroke
				(width 0.1)
				(type default)
			)
			(layer "F.Fab")
		)
		(fp_line
			(start 0.12065 -0.2794)
			(end 0.12065 -0.3048)
			(stroke
				(width 0.1)
				(type default)
			)
			(layer "F.Fab")
		)
		(fp_line
			(start 0.12065 -0.3048)
			(end 0.67945 -0.3048)
			(stroke
				(width 0.1)
				(type default)
			)
			(layer "F.Fab")
		)
		(fp_line
			(start 0.67945 -0.3048)
			(end 0.67945 0.3048)
			(stroke
				(width 0.1)
				(type default)
			)
			(layer "F.Fab")
		)
		(fp_line
			(start -0.67945 -0.305054)
			(end -0.12065 -0.305054)
			(stroke
				(width 0.1)
				(type default)
			)
			(layer "F.Fab")
		)
		(fp_line
			(start -0.12065 -0.305054)
			(end -0.12065 -0.2794)
			(stroke
				(width 0.1)
				(type default)
			)
			(layer "F.Fab")
		)
		(pad "1" smd circle
			(at -0.40005 0 270)
			(size 0 0)
			(layers "F.Cu" "F.Mask" "F.Paste")
			(net "SMB_PDB_FAN_1_SCL")
		)
		(pad "2" smd circle
			(at 0.40005 0 270)
			(size 0 0)
			(layers "F.Cu" "F.Mask" "F.Paste")
			(net "SMB_PDB_FAN_1_R_SCL")
		)
	)
	(footprint ""
		(layer "F.Cu")
		(at 397.637 -58.42)
		(property "Reference" "PC43"
			(at -8.8646 -4.67233 0)
			(unlocked yes)
			(layer "F.SilkS")
			(effects
				(font
					(size 0.7874 0.5842)
					(thickness 0.1524)
				)
				(justify left)
			)
		)
		(property "Value" ""
			(at 0 0 0)
			(layer "F.Fab")
			(effects
				(font
					(size 1.27 1.27)
				)
			)
		)
		(duplicate_pad_numbers_are_jumpers no)
		(fp_line
			(start -9.253728 3.750056)
			(end 9.249918 3.750056)
			(stroke
				(width 0.1524)
				(type default)
			)
			(layer "F.SilkS")
		)
		(fp_line
			(start 0 3.750056)
			(end -9.253728 3.750056)
			(stroke
				(width 0.1524)
				(type default)
			)
			(layer "F.SilkS")
		)
		(fp_circle
			(center 0 3.750056)
			(end 9.249918 3.750056)
			(stroke
				(width 0.1524)
				(type default)
			)
			(fill no)
			(layer "F.SilkS")
		)
		(fp_poly
			(pts
				(arc
					(start 9.249918 3.750056)
					(mid 0 12.999974)
					(end -9.249918 3.750056)
				)
			)
			(stroke
				(width 0)
				(type default)
			)
			(fill yes)
			(layer "F.SilkS")
		)
		(fp_circle
			(center 0 3.750056)
			(end 9.249918 3.750056)
			(stroke
				(width 0.1)
				(type default)
			)
			(fill no)
			(layer "F.Fab")
		)
		(pad "1" thru_hole rect
			(at 0 0)
			(size 1.778 1.778)
			(drill 1.27)
			(layers "*.Cu" "*.Mask")
			(remove_unused_layers no)
			(net "P52V_HS1")
			(clearance 0)
			(padstack
				(mode front_inner_back)
				(layer "Inner"
					(shape circle)
					(size 1.778 1.778)
					(clearance 0)
				)
				(layer "B.Cu"
					(shape rect)
					(size 1.778 1.778)
					(clearance 0)
				)
			)
		)
		(pad "2" thru_hole circle
			(at 0 7.500112)
			(size 1.778 1.778)
			(drill 1.27)
			(layers "*.Cu" "*.Mask")
			(remove_unused_layers no)
			(net "GND")
			(clearance 0)
		)
	)
	(footprint ""
		(layer "F.Cu")
		(at 278.6634 -73.025 180)
		(property "Reference" "R372"
			(at 0 0 180)
			(layer "F.SilkS")
			(hide yes)
			(effects
				(font
					(size 1.27 1.27)
				)
			)
		)
		(property "Value" ""
			(at 0 0 180)
			(layer "F.Fab")
			(effects
				(font
					(size 1.27 1.27)
				)
			)
		)
		(duplicate_pad_numbers_are_jumpers no)
		(fp_line
			(start 0.7874 0.4064)
			(end -0.7874 0.4064)
			(stroke
				(width 0.1524)
				(type default)
			)
			(layer "F.SilkS")
		)
		(fp_line
			(start 0.7874 -0.4064)
			(end 0.7874 0.4064)
			(stroke
				(width 0.1524)
				(type default)
			)
			(layer "F.SilkS")
		)
		(fp_line
			(start -0.7874 0.4064)
			(end -0.7874 -0.4064)
			(stroke
				(width 0.1524)
				(type default)
			)
			(layer "F.SilkS")
		)
		(fp_line
			(start -0.7874 -0.4064)
			(end 0.7874 -0.4064)
			(stroke
				(width 0.1524)
				(type default)
			)
			(layer "F.SilkS")
		)
		(fp_line
			(start 0.67945 0.3048)
			(end 0.120396 0.3048)
			(stroke
				(width 0.1)
				(type default)
			)
			(layer "F.Fab")
		)
		(fp_line
			(start 0.67945 -0.3048)
			(end 0.67945 0.3048)
			(stroke
				(width 0.1)
				(type default)
			)
			(layer "F.Fab")
		)
		(fp_line
			(start 0.12065 -0.2794)
			(end 0.12065 -0.3048)
			(stroke
				(width 0.1)
				(type default)
			)
			(layer "F.Fab")
		)
		(fp_line
			(start 0.12065 -0.3048)
			(end 0.67945 -0.3048)
			(stroke
				(width 0.1)
				(type default)
			)
			(layer "F.Fab")
		)
		(fp_line
			(start 0.120396 0.3048)
			(end 0.120396 0.2794)
			(stroke
				(width 0.1)
				(type default)
			)
			(layer "F.Fab")
		)
		(fp_line
			(start 0.120396 0.2794)
			(end -0.12065 0.2794)
			(stroke
				(width 0.1)
				(type default)
			)
			(layer "F.Fab")
		)
		(fp_line
			(start -0.12065 0.3048)
			(end -0.67945 0.3048)
			(stroke
				(width 0.1)
				(type default)
			)
			(layer "F.Fab")
		)
		(fp_line
			(start -0.12065 0.2794)
			(end -0.12065 0.3048)
			(stroke
				(width 0.1)
				(type default)
			)
			(layer "F.Fab")
		)
		(fp_line
			(start -0.12065 -0.2794)
			(end 0.12065 -0.2794)
			(stroke
				(width 0.1)
				(type default)
			)
			(layer "F.Fab")
		)
		(fp_line
			(start -0.12065 -0.305054)
			(end -0.12065 -0.2794)
			(stroke
				(width 0.1)
				(type default)
			)
			(layer "F.Fab")
		)
		(fp_line
			(start -0.67945 0.3048)
			(end -0.67945 -0.305054)
			(stroke
				(width 0.1)
				(type default)
			)
			(layer "F.Fab")
		)
		(fp_line
			(start -0.67945 -0.305054)
			(end -0.12065 -0.305054)
			(stroke
				(width 0.1)
				(type default)
			)
			(layer "F.Fab")
		)
		(pad "1" smd circle
			(at -0.40005 0 180)
			(size 0 0)
			(layers "F.Cu" "F.Mask" "F.Paste")
			(net "P52V_HS1_VCAP")
		)
		(pad "2" smd circle
			(at 0.40005 0 180)
			(size 0 0)
			(layers "F.Cu" "F.Mask" "F.Paste")
			(net "P52V_HS1_ADR1")
		)
	)
	(footprint ""
		(layer "F.Cu")
		(at 61.92139 -58.42)
		(property "Reference" "PC47"
			(at -8.17499 -5.05333 0)
			(unlocked yes)
			(layer "F.SilkS")
			(effects
				(font
					(size 0.7874 0.5842)
					(thickness 0.1524)
				)
				(justify left)
			)
		)
		(property "Value" ""
			(at 0 0 0)
			(layer "F.Fab")
			(effects
				(font
					(size 1.27 1.27)
				)
			)
		)
		(duplicate_pad_numbers_are_jumpers no)
		(fp_line
			(start -9.253728 3.750056)
			(end 9.249918 3.750056)
			(stroke
				(width 0.1524)
				(type default)
			)
			(layer "F.SilkS")
		)
		(fp_line
			(start 0 3.750056)
			(end -9.253728 3.750056)
			(stroke
				(width 0.1524)
				(type default)
			)
			(layer "F.SilkS")
		)
		(fp_circle
			(center 0 3.750056)
			(end 9.249918 3.750056)
			(stroke
				(width 0.1524)
				(type default)
			)
			(fill no)
			(layer "F.SilkS")
		)
		(fp_poly
			(pts
				(arc
					(start 9.249918 3.750056)
					(mid 0 12.999974)
					(end -9.249918 3.750056)
				)
			)
			(stroke
				(width 0)
				(type default)
			)
			(fill yes)
			(layer "F.SilkS")
		)
		(fp_circle
			(center 0 3.750056)
			(end 9.249918 3.750056)
			(stroke
				(width 0.1)
				(type default)
			)
			(fill no)
			(layer "F.Fab")
		)
		(pad "1" thru_hole rect
			(at 0 0)
			(size 1.778 1.778)
			(drill 1.27)
			(layers "*.Cu" "*.Mask")
			(remove_unused_layers no)
			(net "P52V_HS2")
			(clearance 0)
			(padstack
				(mode front_inner_back)
				(layer "Inner"
					(shape circle)
					(size 1.778 1.778)
					(clearance 0)
				)
				(layer "B.Cu"
					(shape rect)
					(size 1.778 1.778)
					(clearance 0)
				)
			)
		)
		(pad "2" thru_hole circle
			(at 0 7.500112)
			(size 1.778 1.778)
			(drill 1.27)
			(layers "*.Cu" "*.Mask")
			(remove_unused_layers no)
			(net "GND")
			(clearance 0)
		)
	)
)
